# T6G (Grand Teton) — schematic netlist excerpt (pin names and nets, part order shuffled) for the footprints in the layout excerpt that follows; sources: Cadence DE-HDL packaged netlist, KiCad conversion of 04192023_DAF0TMB3IC0_F0TG_MB_C_brd_V02_OCP.brd

C1095  Q_CAP  0.1UF 25V 10% X7R  pkg 0402  page 258 : A = P3V3_ADC128_2_VCC ; B = GND
C1128  Q_CAP  0.1UF 16V 10% X7R  pkg C0402  page 83 : A = P1V8_AUX ; B = GND

(kicad_pcb
	(version 20260206)
	(generator "pcbnew")
	(generator_version "10.0")
	(general
		(thickness 1.6)
		(legacy_teardrops no)
	)
	(paper "A4")
	(title_block
		(title "04192023_DAF0TMB3IC0_F0TG_MB_C_brd_V02_OCP.brd")
		(comment 1 "Grand Teton / footprints 5247-5248 of 8354")
	)
	(layers
		(0 "F.Cu" signal "TOP")
		(4 "In1.Cu" signal "GND")
		(6 "In2.Cu" signal "IN1")
		(8 "In3.Cu" signal "GND1")
		(10 "In4.Cu" signal "IN2")
		(12 "In5.Cu" signal "GND2")
		(14 "In6.Cu" signal "IN3")
		(16 "In7.Cu" signal "GND3")
		(18 "In8.Cu" signal "VCC")
		(20 "In9.Cu" signal "VCC1")
		(22 "In10.Cu" signal "GND4")
		(24 "In11.Cu" signal "IN4")
		(26 "In12.Cu" signal "GND5")
		(28 "In13.Cu" signal "IN5")
		(30 "In14.Cu" signal "GND6")
		(32 "In15.Cu" signal "IN6")
		(34 "In16.Cu" signal "GND7")
		(2 "B.Cu" signal "BOTTOM")
		(9 "F.Adhes" user "F.Adhesive")
		(11 "B.Adhes" user "B.Adhesive")
		(13 "F.Paste" user "Package Geometry/Pastemask Top")
		(15 "B.Paste" user "Package Geometry/Pastemask Bottom")
		(5 "F.SilkS" user "Ref Des/Silkscreen Top")
		(7 "B.SilkS" user "Ref Des/Silkscreen Bottom")
		(1 "F.Mask" user "Board Geometry/Soldermask Top")
		(3 "B.Mask" user "Board Geometry/Soldermask Bottom")
		(17 "Dwgs.User" user "User.Drawings")
		(19 "Cmts.User" user "User.Comments")
		(21 "Eco1.User" user "User.Eco1")
		(23 "Eco2.User" user "User.Eco2")
		(25 "Edge.Cuts" user "Board Geometry/Outline")
		(27 "Margin" user)
		(31 "F.CrtYd" user "Package Geometry/Place Bound Top")
		(29 "B.CrtYd" user "Package Geometry/Place Bound Bottom")
		(35 "F.Fab" user "Ref Des/Assembly Top")
		(33 "B.Fab" user "Ref Des/Assembly Bottom")
	)
	(footprint ""
		(layer "B.Cu")
		(at 187.511944 -117.442996 90)
		(property "Reference" "C1128"
			(at 0 0 90)
			(layer "B.SilkS")
			(hide yes)
			(effects
				(font
					(size 1.27 1.27)
				)
				(justify mirror)
			)
		)
		(property "Value" ""
			(at 0 0 90)
			(layer "B.Fab")
			(effects
				(font
					(size 1.27 1.27)
				)
				(justify mirror)
			)
		)
		(duplicate_pad_numbers_are_jumpers no)
		(fp_line
			(start 0.69215 -0.2921)
			(end -0.69215 -0.2921)
			(stroke
				(width 0.1524)
				(type default)
			)
			(layer "B.SilkS")
		)
		(fp_line
			(start -0.69215 -0.2921)
			(end -0.69215 0.2921)
			(stroke
				(width 0.1524)
				(type default)
			)
			(layer "B.SilkS")
		)
		(fp_line
			(start 0.69215 0.2921)
			(end 0.69215 -0.2921)
			(stroke
				(width 0.1524)
				(type default)
			)
			(layer "B.SilkS")
		)
		(fp_line
			(start -0.69215 0.2921)
			(end 0.69215 0.2921)
			(stroke
				(width 0.1524)
				(type default)
			)
			(layer "B.SilkS")
		)
		(fp_line
			(start 0.51435 -0.2794)
			(end -0.51435 -0.2794)
			(stroke
				(width 0.1)
				(type default)
			)
			(layer "B.Fab")
		)
		(fp_line
			(start -0.51435 -0.2794)
			(end -0.51435 0.2794)
			(stroke
				(width 0.1)
				(type default)
			)
			(layer "B.Fab")
		)
		(fp_line
			(start 0.51435 0.2794)
			(end 0.51435 -0.2794)
			(stroke
				(width 0.1)
				(type default)
			)
			(layer "B.Fab")
		)
		(fp_line
			(start -0.51435 0.2794)
			(end 0.51435 0.2794)
			(stroke
				(width 0.1)
				(type default)
			)
			(layer "B.Fab")
		)
		(pad "1" smd circle
			(at 0.40005 0 270)
			(size 0 0)
			(layers "B.Cu" "B.Mask" "B.Paste")
			(net "P1V8_AUX")
		)
		(pad "2" smd circle
			(at -0.40005 0 270)
			(size 0 0)
			(layers "B.Cu" "B.Mask" "B.Paste")
			(net "GND")
		)
		(zone
			(layer "B.Cu")
			(hatch none 0.5)
			(connect_pads
				(clearance 0)
			)
			(min_thickness 0.25)
			(keepout
				(tracks not_allowed)
				(vias allowed)
				(pads allowed)
				(copperpour not_allowed)
				(footprints allowed)
			)
			(placement
				(enabled no)
				(sheetname "")
			)
			(fill
				(thermal_gap 0.5)
				(thermal_bridge_width 0.5)
				(island_removal_mode 0)
			)
			(polygon
				(pts
					(xy 187.365894 -117.342666) (xy 187.365894 -117.542056) (xy 187.42406 -117.633496) (xy 187.599574 -117.633496)
					(xy 187.65774 -117.542056) (xy 187.65774 -117.342666) (xy 187.599574 -117.252496) (xy 187.424314 -117.252496)
				)
			)
		)
	)
	(footprint ""
		(layer "B.Cu")
		(at 213.285578 -326.509888)
		(property "Reference" "C1095"
			(at 0 0 0)
			(layer "B.SilkS")
			(hide yes)
			(effects
				(font
					(size 1.27 1.27)
				)
				(justify mirror)
			)
		)
		(property "Value" ""
			(at 0 0 0)
			(layer "B.Fab")
			(effects
				(font
					(size 1.27 1.27)
				)
				(justify mirror)
			)
		)
		(duplicate_pad_numbers_are_jumpers no)
		(fp_line
			(start -0.7874 -0.4064)
			(end -0.7874 0.4064)
			(stroke
				(width 0.1524)
				(type default)
			)
			(layer "B.SilkS")
		)
		(fp_line
			(start -0.7874 0.4064)
			(end 0.7874 0.4064)
			(stroke
				(width 0.1524)
				(type default)
			)
			(layer "B.SilkS")
		)
		(fp_line
			(start 0.7874 -0.4064)
			(end -0.7874 -0.4064)
			(stroke
				(width 0.1524)
				(type default)
			)
			(layer "B.SilkS")
		)
		(fp_line
			(start 0.7874 0.4064)
			(end 0.7874 -0.4064)
			(stroke
				(width 0.1524)
				(type default)
			)
			(layer "B.SilkS")
		)
		(fp_line
			(start -0.67945 -0.3048)
			(end -0.67945 0.3048)
			(stroke
				(width 0.1)
				(type default)
			)
			(layer "B.Fab")
		)
		(fp_line
			(start -0.67945 0.3048)
			(end -0.120396 0.3048)
			(stroke
				(width 0.1)
				(type default)
			)
			(layer "B.Fab")
		)
		(fp_line
			(start -0.12065 -0.3048)
			(end -0.67945 -0.3048)
			(stroke
				(width 0.1)
				(type default)
			)
			(layer "B.Fab")
		)
		(fp_line
			(start -0.12065 -0.2794)
			(end -0.12065 -0.3048)
			(stroke
				(width 0.1)
				(type default)
			)
			(layer "B.Fab")
		)
		(fp_line
			(start -0.120396 0.2794)
			(end 0.12065 0.2794)
			(stroke
				(width 0.1)
				(type default)
			)
			(layer "B.Fab")
		)
		(fp_line
			(start -0.120396 0.3048)
			(end -0.120396 0.2794)
			(stroke
				(width 0.1)
				(type default)
			)
			(layer "B.Fab")
		)
		(fp_line
			(start 0.12065 -0.305054)
			(end 0.12065 -0.2794)
			(stroke
				(width 0.1)
				(type default)
			)
			(layer "B.Fab")
		)
		(fp_line
			(start 0.12065 -0.2794)
			(end -0.12065 -0.2794)
			(stroke
				(width 0.1)
				(type default)
			)
			(layer "B.Fab")
		)
		(fp_line
			(start 0.12065 0.2794)
			(end 0.12065 0.3048)
			(stroke
				(width 0.1)
				(type default)
			)
			(layer "B.Fab")
		)
		(fp_line
			(start 0.12065 0.3048)
			(end 0.67945 0.3048)
			(stroke
				(width 0.1)
				(type default)
			)
			(layer "B.Fab")
		)
		(fp_line
			(start 0.67945 -0.305054)
			(end 0.12065 -0.305054)
			(stroke
				(width 0.1)
				(type default)
			)
			(layer "B.Fab")
		)
		(fp_line
			(start 0.67945 0.3048)
			(end 0.67945 -0.305054)
			(stroke
				(width 0.1)
				(type default)
			)
			(layer "B.Fab")
		)
		(pad "1" smd circle
			(at 0.40005 0 180)
			(size 0 0)
			(layers "B.Cu" "B.Mask" "B.Paste")
			(net "P3V3_ADC128_2_VCC")
		)
		(pad "2" smd circle
			(at -0.40005 0 180)
			(size 0 0)
			(layers "B.Cu" "B.Mask" "B.Paste")
			(net "GND")
		)
	)
)
